(kicad_pcb
	(version 20260206)
	(generator "pcbnew")
	(generator_version "10.0")
	(general
		(thickness 1.6)
		(legacy_teardrops no)
	)
	(paper "A4")
	(title_block
		(title "01162023_DA0F0TEBIF0_F0T_Expander_BD_F_brd_V02_OCP.brd")
		(comment 1 "Grand Teton / footprints 1542-1549 of 9728")
	)
	(layers
		(0 "F.Cu" signal "TOP")
		(4 "In1.Cu" signal "GND")
		(6 "In2.Cu" signal "VCC")
		(8 "In3.Cu" signal "VCC1")
		(10 "In4.Cu" signal "GND1")
		(12 "In5.Cu" signal "IN1")
		(14 "In6.Cu" signal "GND2")
		(16 "In7.Cu" signal "IN2")
		(18 "In8.Cu" signal "GND3")
		(20 "In9.Cu" signal "IN3")
		(22 "In10.Cu" signal "GND4")
		(24 "In11.Cu" signal "IN4")
		(26 "In12.Cu" signal "GND5")
		(28 "In13.Cu" signal "IN5")
		(30 "In14.Cu" signal "GND6")
		(32 "In15.Cu" signal "IN6")
		(34 "In16.Cu" signal "GND7")
		(2 "B.Cu" signal "BOTTOM")
		(9 "F.Adhes" user "F.Adhesive")
		(11 "B.Adhes" user "B.Adhesive")
		(13 "F.Paste" user "Package Geometry/Pastemask Top")
		(15 "B.Paste" user "Package Geometry/Pastemask Bottom")
		(5 "F.SilkS" user "Ref Des/Silkscreen Top")
		(7 "B.SilkS" user "Ref Des/Silkscreen Bottom")
		(1 "F.Mask" user "Board Geometry/Soldermask Top")
		(3 "B.Mask" user "Board Geometry/Soldermask Bottom")
		(17 "Dwgs.User" user "User.Drawings")
		(19 "Cmts.User" user "User.Comments")
		(21 "Eco1.User" user "User.Eco1")
		(23 "Eco2.User" user "User.Eco2")
		(25 "Edge.Cuts" user "Board Geometry/Outline")
		(27 "Margin" user)
		(31 "F.CrtYd" user "Package Geometry/Place Bound Top")
		(29 "B.CrtYd" user "Package Geometry/Place Bound Bottom")
		(35 "F.Fab" user "Ref Des/Assembly Top")
		(33 "B.Fab" user "Ref Des/Assembly Bottom")
	)
	(footprint ""
		(layer "F.Cu")
		(at 113.032032 -162.782504)
		(property "Reference" "R824"
			(at 0 0 0)
			(layer "F.SilkS")
			(hide yes)
			(effects
				(font
					(size 1.27 1.27)
				)
			)
		)
		(property "Value" ""
			(at 0 0 0)
			(layer "F.Fab")
			(effects
				(font
					(size 1.27 1.27)
				)
			)
		)
		(duplicate_pad_numbers_are_jumpers no)
		(fp_line
			(start -0.7874 -0.4064)
			(end 0.7874 -0.4064)
			(stroke
				(width 0.1524)
				(type default)
			)
			(layer "F.SilkS")
		)
		(fp_line
			(start -0.7874 0.4064)
			(end -0.7874 -0.4064)
			(stroke
				(width 0.1524)
				(type default)
			)
			(layer "F.SilkS")
		)
		(fp_line
			(start 0.7874 -0.4064)
			(end 0.7874 0.4064)
			(stroke
				(width 0.1524)
				(type default)
			)
			(layer "F.SilkS")
		)
		(fp_line
			(start 0.7874 0.4064)
			(end -0.7874 0.4064)
			(stroke
				(width 0.1524)
				(type default)
			)
			(layer "F.SilkS")
		)
		(fp_line
			(start -0.67945 -0.305054)
			(end -0.12065 -0.305054)
			(stroke
				(width 0.1)
				(type default)
			)
			(layer "F.Fab")
		)
		(fp_line
			(start -0.67945 0.3048)
			(end -0.67945 -0.305054)
			(stroke
				(width 0.1)
				(type default)
			)
			(layer "F.Fab")
		)
		(fp_line
			(start -0.12065 -0.305054)
			(end -0.12065 -0.2794)
			(stroke
				(width 0.1)
				(type default)
			)
			(layer "F.Fab")
		)
		(fp_line
			(start -0.12065 -0.2794)
			(end 0.12065 -0.2794)
			(stroke
				(width 0.1)
				(type default)
			)
			(layer "F.Fab")
		)
		(fp_line
			(start -0.12065 0.2794)
			(end -0.12065 0.3048)
			(stroke
				(width 0.1)
				(type default)
			)
			(layer "F.Fab")
		)
		(fp_line
			(start -0.12065 0.3048)
			(end -0.67945 0.3048)
			(stroke
				(width 0.1)
				(type default)
			)
			(layer "F.Fab")
		)
		(fp_line
			(start 0.120396 0.2794)
			(end -0.12065 0.2794)
			(stroke
				(width 0.1)
				(type default)
			)
			(layer "F.Fab")
		)
		(fp_line
			(start 0.120396 0.3048)
			(end 0.120396 0.2794)
			(stroke
				(width 0.1)
				(type default)
			)
			(layer "F.Fab")
		)
		(fp_line
			(start 0.12065 -0.3048)
			(end 0.67945 -0.3048)
			(stroke
				(width 0.1)
				(type default)
			)
			(layer "F.Fab")
		)
		(fp_line
			(start 0.12065 -0.2794)
			(end 0.12065 -0.3048)
			(stroke
				(width 0.1)
				(type default)
			)
			(layer "F.Fab")
		)
		(fp_line
			(start 0.67945 -0.3048)
			(end 0.67945 0.3048)
			(stroke
				(width 0.1)
				(type default)
			)
			(layer "F.Fab")
		)
		(fp_line
			(start 0.67945 0.3048)
			(end 0.120396 0.3048)
			(stroke
				(width 0.1)
				(type default)
			)
			(layer "F.Fab")
		)
		(pad "1" smd circle
			(at -0.40005 0)
			(size 0 0)
			(layers "F.Cu" "F.Mask" "F.Paste")
			(net "P3V3_AUX_EN")
		)
		(pad "2" smd circle
			(at 0.40005 0)
			(size 0 0)
			(layers "F.Cu" "F.Mask" "F.Paste")
			(net "PWRGD_P5V_AUX_R")
		)
	)
	(footprint ""
		(layer "F.Cu")
		(at 320.852292 -114.384836 180)
		(property "Reference" "PC907"
			(at 0 0 180)
			(layer "F.SilkS")
			(hide yes)
			(effects
				(font
					(size 1.27 1.27)
				)
			)
		)
		(property "Value" ""
			(at 0 0 180)
			(layer "F.Fab")
			(effects
				(font
					(size 1.27 1.27)
				)
			)
		)
		(duplicate_pad_numbers_are_jumpers no)
		(fp_line
			(start 0.7874 0.4064)
			(end -0.7874 0.4064)
			(stroke
				(width 0.1524)
				(type default)
			)
			(layer "F.SilkS")
		)
		(fp_line
			(start 0.7874 -0.4064)
			(end 0.7874 0.4064)
			(stroke
				(width 0.1524)
				(type default)
			)
			(layer "F.SilkS")
		)
		(fp_line
			(start -0.7874 0.4064)
			(end -0.7874 -0.4064)
			(stroke
				(width 0.1524)
				(type default)
			)
			(layer "F.SilkS")
		)
		(fp_line
			(start -0.7874 -0.4064)
			(end 0.7874 -0.4064)
			(stroke
				(width 0.1524)
				(type default)
			)
			(layer "F.SilkS")
		)
		(fp_line
			(start 0.67945 0.3048)
			(end 0.120396 0.3048)
			(stroke
				(width 0.1)
				(type default)
			)
			(layer "F.Fab")
		)
		(fp_line
			(start 0.67945 -0.3048)
			(end 0.67945 0.3048)
			(stroke
				(width 0.1)
				(type default)
			)
			(layer "F.Fab")
		)
		(fp_line
			(start 0.12065 -0.2794)
			(end 0.12065 -0.3048)
			(stroke
				(width 0.1)
				(type default)
			)
			(layer "F.Fab")
		)
		(fp_line
			(start 0.12065 -0.3048)
			(end 0.67945 -0.3048)
			(stroke
				(width 0.1)
				(type default)
			)
			(layer "F.Fab")
		)
		(fp_line
			(start 0.120396 0.3048)
			(end 0.120396 0.2794)
			(stroke
				(width 0.1)
				(type default)
			)
			(layer "F.Fab")
		)
		(fp_line
			(start 0.120396 0.2794)
			(end -0.12065 0.2794)
			(stroke
				(width 0.1)
				(type default)
			)
			(layer "F.Fab")
		)
		(fp_line
			(start -0.12065 0.3048)
			(end -0.67945 0.3048)
			(stroke
				(width 0.1)
				(type default)
			)
			(layer "F.Fab")
		)
		(fp_line
			(start -0.12065 0.2794)
			(end -0.12065 0.3048)
			(stroke
				(width 0.1)
				(type default)
			)
			(layer "F.Fab")
		)
		(fp_line
			(start -0.12065 -0.2794)
			(end 0.12065 -0.2794)
			(stroke
				(width 0.1)
				(type default)
			)
			(layer "F.Fab")
		)
		(fp_line
			(start -0.12065 -0.305054)
			(end -0.12065 -0.2794)
			(stroke
				(width 0.1)
				(type default)
			)
			(layer "F.Fab")
		)
		(fp_line
			(start -0.67945 0.3048)
			(end -0.67945 -0.305054)
			(stroke
				(width 0.1)
				(type default)
			)
			(layer "F.Fab")
		)
		(fp_line
			(start -0.67945 -0.305054)
			(end -0.12065 -0.305054)
			(stroke
				(width 0.1)
				(type default)
			)
			(layer "F.Fab")
		)
		(pad "1" smd circle
			(at -0.40005 0 180)
			(size 0 0)
			(layers "F.Cu" "F.Mask" "F.Paste")
			(net "P3V3_NIC5_CO_DV_DT")
		)
		(pad "2" smd circle
			(at 0.40005 0 180)
			(size 0 0)
			(layers "F.Cu" "F.Mask" "F.Paste")
			(net "GND")
		)
	)
	(footprint ""
		(layer "F.Cu")
		(at 251.56287 -81.2165 90)
		(property "Reference" "C2637"
			(at 0 0 90)
			(layer "F.SilkS")
			(hide yes)
			(effects
				(font
					(size 1.27 1.27)
				)
			)
		)
		(property "Value" ""
			(at 0 0 90)
			(layer "F.Fab")
			(effects
				(font
					(size 1.27 1.27)
				)
			)
		)
		(duplicate_pad_numbers_are_jumpers no)
		(fp_line
			(start 0.7874 -0.4064)
			(end 0.7874 0.4064)
			(stroke
				(width 0.1524)
				(type default)
			)
			(layer "F.SilkS")
		)
		(fp_line
			(start -0.7874 -0.4064)
			(end 0.7874 -0.4064)
			(stroke
				(width 0.1524)
				(type default)
			)
			(layer "F.SilkS")
		)
		(fp_line
			(start 0.7874 0.4064)
			(end -0.7874 0.4064)
			(stroke
				(width 0.1524)
				(type default)
			)
			(layer "F.SilkS")
		)
		(fp_line
			(start -0.7874 0.4064)
			(end -0.7874 -0.4064)
			(stroke
				(width 0.1524)
				(type default)
			)
			(layer "F.SilkS")
		)
		(fp_line
			(start -0.12065 -0.305054)
			(end -0.12065 -0.2794)
			(stroke
				(width 0.1)
				(type default)
			)
			(layer "F.Fab")
		)
		(fp_line
			(start -0.67945 -0.305054)
			(end -0.12065 -0.305054)
			(stroke
				(width 0.1)
				(type default)
			)
			(layer "F.Fab")
		)
		(fp_line
			(start 0.67945 -0.3048)
			(end 0.67945 0.3048)
			(stroke
				(width 0.1)
				(type default)
			)
			(layer "F.Fab")
		)
		(fp_line
			(start 0.12065 -0.3048)
			(end 0.67945 -0.3048)
			(stroke
				(width 0.1)
				(type default)
			)
			(layer "F.Fab")
		)
		(fp_line
			(start 0.12065 -0.2794)
			(end 0.12065 -0.3048)
			(stroke
				(width 0.1)
				(type default)
			)
			(layer "F.Fab")
		)
		(fp_line
			(start -0.12065 -0.2794)
			(end 0.12065 -0.2794)
			(stroke
				(width 0.1)
				(type default)
			)
			(layer "F.Fab")
		)
		(fp_line
			(start 0.120396 0.2794)
			(end -0.12065 0.2794)
			(stroke
				(width 0.1)
				(type default)
			)
			(layer "F.Fab")
		)
		(fp_line
			(start -0.12065 0.2794)
			(end -0.12065 0.3048)
			(stroke
				(width 0.1)
				(type default)
			)
			(layer "F.Fab")
		)
		(fp_line
			(start 0.67945 0.3048)
			(end 0.120396 0.3048)
			(stroke
				(width 0.1)
				(type default)
			)
			(layer "F.Fab")
		)
		(fp_line
			(start 0.120396 0.3048)
			(end 0.120396 0.2794)
			(stroke
				(width 0.1)
				(type default)
			)
			(layer "F.Fab")
		)
		(fp_line
			(start -0.12065 0.3048)
			(end -0.67945 0.3048)
			(stroke
				(width 0.1)
				(type default)
			)
			(layer "F.Fab")
		)
		(fp_line
			(start -0.67945 0.3048)
			(end -0.67945 -0.305054)
			(stroke
				(width 0.1)
				(type default)
			)
			(layer "F.Fab")
		)
		(pad "1" smd circle
			(at -0.40005 0 90)
			(size 0 0)
			(layers "F.Cu" "F.Mask" "F.Paste")
			(net "XTAL_CK440_25M_XOUT")
		)
		(pad "2" smd circle
			(at 0.40005 0 90)
			(size 0 0)
			(layers "F.Cu" "F.Mask" "F.Paste")
			(net "GND")
		)
	)
	(footprint ""
		(layer "F.Cu")
		(at 418.919914 -15.649956 180)
		(property "Reference" "H114"
			(at -5.614416 0.421894 0)
			(unlocked yes)
			(layer "B.SilkS")
			(effects
				(font
					(size 0.7874 0.5842)
					(thickness 0.1524)
				)
				(justify left mirror)
			)
		)
		(property "Value" ""
			(at 0 0 180)
			(layer "F.Fab")
			(effects
				(font
					(size 1.27 1.27)
				)
			)
		)
		(duplicate_pad_numbers_are_jumpers no)
		(pad "1" thru_hole rect
			(at 0 0 180)
			(size 4.2164 5.0038)
			(drill 2.0066
				(offset 0.099822 0)
			)
			(layers "*.Cu" "*.Mask")
			(remove_unused_layers no)
			(net "Net_8549")
			(clearance -0.8509)
			(padstack
				(mode front_inner_back)
				(layer "Inner"
					(shape circle)
					(size 4.0132 4.0132)
					(clearance -0.7493)
				)
				(layer "B.Cu"
					(shape circle)
					(size 4.0132 4.0132)
					(clearance -0.7493)
				)
			)
		)
	)
	(footprint ""
		(layer "F.Cu")
		(at 101.930454 -118.76024 180)
		(property "Reference" "R5859"
			(at 0 0 180)
			(layer "F.SilkS")
			(hide yes)
			(effects
				(font
					(size 1.27 1.27)
				)
			)
		)
		(property "Value" ""
			(at 0 0 180)
			(layer "F.Fab")
			(effects
				(font
					(size 1.27 1.27)
				)
			)
		)
		(duplicate_pad_numbers_are_jumpers no)
		(fp_line
			(start 0.7874 0.4064)
			(end -0.7874 0.4064)
			(stroke
				(width 0.1524)
				(type default)
			)
			(layer "F.SilkS")
		)
		(fp_line
			(start 0.7874 -0.4064)
			(end 0.7874 0.4064)
			(stroke
				(width 0.1524)
				(type default)
			)
			(layer "F.SilkS")
		)
		(fp_line
			(start -0.7874 0.4064)
			(end -0.7874 -0.4064)
			(stroke
				(width 0.1524)
				(type default)
			)
			(layer "F.SilkS")
		)
		(fp_line
			(start -0.7874 -0.4064)
			(end 0.7874 -0.4064)
			(stroke
				(width 0.1524)
				(type default)
			)
			(layer "F.SilkS")
		)
		(fp_line
			(start 0.67945 0.3048)
			(end 0.120396 0.3048)
			(stroke
				(width 0.1)
				(type default)
			)
			(layer "F.Fab")
		)
		(fp_line
			(start 0.67945 -0.3048)
			(end 0.67945 0.3048)
			(stroke
				(width 0.1)
				(type default)
			)
			(layer "F.Fab")
		)
		(fp_line
			(start 0.12065 -0.2794)
			(end 0.12065 -0.3048)
			(stroke
				(width 0.1)
				(type default)
			)
			(layer "F.Fab")
		)
		(fp_line
			(start 0.12065 -0.3048)
			(end 0.67945 -0.3048)
			(stroke
				(width 0.1)
				(type default)
			)
			(layer "F.Fab")
		)
		(fp_line
			(start 0.120396 0.3048)
			(end 0.120396 0.2794)
			(stroke
				(width 0.1)
				(type default)
			)
			(layer "F.Fab")
		)
		(fp_line
			(start 0.120396 0.2794)
			(end -0.12065 0.2794)
			(stroke
				(width 0.1)
				(type default)
			)
			(layer "F.Fab")
		)
		(fp_line
			(start -0.12065 0.3048)
			(end -0.67945 0.3048)
			(stroke
				(width 0.1)
				(type default)
			)
			(layer "F.Fab")
		)
		(fp_line
			(start -0.12065 0.2794)
			(end -0.12065 0.3048)
			(stroke
				(width 0.1)
				(type default)
			)
			(layer "F.Fab")
		)
		(fp_line
			(start -0.12065 -0.2794)
			(end 0.12065 -0.2794)
			(stroke
				(width 0.1)
				(type default)
			)
			(layer "F.Fab")
		)
		(fp_line
			(start -0.12065 -0.305054)
			(end -0.12065 -0.2794)
			(stroke
				(width 0.1)
				(type default)
			)
			(layer "F.Fab")
		)
		(fp_line
			(start -0.67945 0.3048)
			(end -0.67945 -0.305054)
			(stroke
				(width 0.1)
				(type default)
			)
			(layer "F.Fab")
		)
		(fp_line
			(start -0.67945 -0.305054)
			(end -0.12065 -0.305054)
			(stroke
				(width 0.1)
				(type default)
			)
			(layer "F.Fab")
		)
		(pad "1" smd circle
			(at -0.40005 0 180)
			(size 0 0)
			(layers "F.Cu" "F.Mask" "F.Paste")
			(net "PWRGD_P3V3_NIC1_D")
		)
		(pad "2" smd circle
			(at 0.40005 0 180)
			(size 0 0)
			(layers "F.Cu" "F.Mask" "F.Paste")
			(net "PWRGD_P3V3_NIC1_R")
		)
	)
	(footprint ""
		(layer "F.Cu")
		(at 139.228576 -260.807708 90)
		(property "Reference" "R5800"
			(at 0 0 90)
			(layer "F.SilkS")
			(hide yes)
			(effects
				(font
					(size 1.27 1.27)
				)
			)
		)
		(property "Value" ""
			(at 0 0 90)
			(layer "F.Fab")
			(effects
				(font
					(size 1.27 1.27)
				)
			)
		)
		(duplicate_pad_numbers_are_jumpers no)
		(fp_line
			(start 0.7874 -0.4064)
			(end 0.7874 0.4064)
			(stroke
				(width 0.1524)
				(type default)
			)
			(layer "F.SilkS")
		)
		(fp_line
			(start -0.7874 -0.4064)
			(end 0.7874 -0.4064)
			(stroke
				(width 0.1524)
				(type default)
			)
			(layer "F.SilkS")
		)
		(fp_line
			(start 0.7874 0.4064)
			(end -0.7874 0.4064)
			(stroke
				(width 0.1524)
				(type default)
			)
			(layer "F.SilkS")
		)
		(fp_line
			(start -0.7874 0.4064)
			(end -0.7874 -0.4064)
			(stroke
				(width 0.1524)
				(type default)
			)
			(layer "F.SilkS")
		)
		(fp_line
			(start -0.12065 -0.305054)
			(end -0.12065 -0.2794)
			(stroke
				(width 0.1)
				(type default)
			)
			(layer "F.Fab")
		)
		(fp_line
			(start -0.67945 -0.305054)
			(end -0.12065 -0.305054)
			(stroke
				(width 0.1)
				(type default)
			)
			(layer "F.Fab")
		)
		(fp_line
			(start 0.67945 -0.3048)
			(end 0.67945 0.3048)
			(stroke
				(width 0.1)
				(type default)
			)
			(layer "F.Fab")
		)
		(fp_line
			(start 0.12065 -0.3048)
			(end 0.67945 -0.3048)
			(stroke
				(width 0.1)
				(type default)
			)
			(layer "F.Fab")
		)
		(fp_line
			(start 0.12065 -0.2794)
			(end 0.12065 -0.3048)
			(stroke
				(width 0.1)
				(type default)
			)
			(layer "F.Fab")
		)
		(fp_line
			(start -0.12065 -0.2794)
			(end 0.12065 -0.2794)
			(stroke
				(width 0.1)
				(type default)
			)
			(layer "F.Fab")
		)
		(fp_line
			(start 0.120396 0.2794)
			(end -0.12065 0.2794)
			(stroke
				(width 0.1)
				(type default)
			)
			(layer "F.Fab")
		)
		(fp_line
			(start -0.12065 0.2794)
			(end -0.12065 0.3048)
			(stroke
				(width 0.1)
				(type default)
			)
			(layer "F.Fab")
		)
		(fp_line
			(start 0.67945 0.3048)
			(end 0.120396 0.3048)
			(stroke
				(width 0.1)
				(type default)
			)
			(layer "F.Fab")
		)
		(fp_line
			(start 0.120396 0.3048)
			(end 0.120396 0.2794)
			(stroke
				(width 0.1)
				(type default)
			)
			(layer "F.Fab")
		)
		(fp_line
			(start -0.12065 0.3048)
			(end -0.67945 0.3048)
			(stroke
				(width 0.1)
				(type default)
			)
			(layer "F.Fab")
		)
		(fp_line
			(start -0.67945 0.3048)
			(end -0.67945 -0.305054)
			(stroke
				(width 0.1)
				(type default)
			)
			(layer "F.Fab")
		)
		(pad "1" smd circle
			(at -0.40005 0 90)
			(size 0 0)
			(layers "F.Cu" "F.Mask" "F.Paste")
			(net "PEX1_SYS_ERR_N_G")
		)
		(pad "2" smd circle
			(at 0.40005 0 90)
			(size 0 0)
			(layers "F.Cu" "F.Mask" "F.Paste")
			(net "PEX1_SYS_ERR_FPGA")
		)
	)
	(footprint ""
		(layer "F.Cu")
		(at 312.857388 -107.552998 -90)
		(property "Reference" "C920"
			(at 0 0 270)
			(layer "F.SilkS")
			(hide yes)
			(effects
				(font
					(size 1.27 1.27)
				)
			)
		)
		(property "Value" ""
			(at 0 0 270)
			(layer "F.Fab")
			(effects
				(font
					(size 1.27 1.27)
				)
			)
		)
		(duplicate_pad_numbers_are_jumpers no)
		(fp_line
			(start -1.524 0.762)
			(end -1.524 -0.762)
			(stroke
				(width 0.1524)
				(type default)
			)
			(layer "F.SilkS")
		)
		(fp_line
			(start 1.524 0.762)
			(end -1.524 0.762)
			(stroke
				(width 0.1524)
				(type default)
			)
			(layer "F.SilkS")
		)
		(fp_line
			(start -1.524 -0.762)
			(end 1.524 -0.762)
			(stroke
				(width 0.1524)
				(type default)
			)
			(layer "F.SilkS")
		)
		(fp_line
			(start 1.524 -0.762)
			(end 1.524 0.762)
			(stroke
				(width 0.1524)
				(type default)
			)
			(layer "F.SilkS")
		)
		(fp_line
			(start -1.1049 0.724916)
			(end 1.1049 0.724916)
			(stroke
				(width 0.1)
				(type default)
			)
			(layer "F.Fab")
		)
		(fp_line
			(start 1.1049 0.724916)
			(end 1.1049 -0.724916)
			(stroke
				(width 0.1)
				(type default)
			)
			(layer "F.Fab")
		)
		(fp_line
			(start -1.1049 -0.724916)
			(end -1.1049 0.724916)
			(stroke
				(width 0.1)
				(type default)
			)
			(layer "F.Fab")
		)
		(fp_line
			(start 1.1049 -0.724916)
			(end -1.1049 -0.724916)
			(stroke
				(width 0.1)
				(type default)
			)
			(layer "F.Fab")
		)
		(pad "1" smd rect
			(at -0.889 0 90)
			(size 1.016 1.27)
			(layers "F.Cu" "F.Mask" "F.Paste")
			(net "P12V_NIC5")
		)
		(pad "2" smd rect
			(at 0.889 0 90)
			(size 1.016 1.27)
			(layers "F.Cu" "F.Mask" "F.Paste")
			(net "GND")
		)
	)
	(footprint ""
		(layer "F.Cu")
		(at 387.580632 -124.605542)
		(property "Reference" "C674"
			(at 0 0 0)
			(layer "F.SilkS")
			(hide yes)
			(effects
				(font
					(size 1.27 1.27)
				)
			)
		)
		(property "Value" ""
			(at 0 0 0)
			(layer "F.Fab")
			(effects
				(font
					(size 1.27 1.27)
				)
			)
		)
		(duplicate_pad_numbers_are_jumpers no)
		(fp_line
			(start -0.299974 -0.150114)
			(end 0.299974 -0.150114)
			(stroke
				(width 0.1)
				(type default)
			)
			(layer "F.Fab")
		)
		(fp_line
			(start -0.299974 0.150114)
			(end -0.299974 -0.150114)
			(stroke
				(width 0.1)
				(type default)
			)
			(layer "F.Fab")
		)
		(fp_line
			(start 0.299974 -0.150114)
			(end 0.299974 0.150114)
			(stroke
				(width 0.1)
				(type default)
			)
			(layer "F.Fab")
		)
		(fp_line
			(start 0.299974 0.150114)
			(end -0.299974 0.150114)
			(stroke
				(width 0.1)
				(type default)
			)
			(layer "F.Fab")
		)
		(pad "1" smd rect
			(at -0.2667 0)
			(size 0.3048 0.381)
			(layers "F.Cu" "F.Mask" "F.Paste")
			(net "P5E_PEX3_STN1_TX_DN<27>")
		)
		(pad "2" smd rect
			(at 0.2667 0)
			(size 0.3048 0.381)
			(layers "F.Cu" "F.Mask" "F.Paste")
			(net "P5E_PEX3_STN1_TX_C_DN<27>")
		)
	)
)
